(kicad_pcb
	(version 20260206)
	(generator "pcbnew")
	(generator_version "10.0")
	(general
		(thickness 1.6)
		(legacy_teardrops no)
	)
	(paper "A4")
	(title_block
		(title "Wiwynn_Tioga_Pass_MB.brd")
		(comment 1 "Tioga Pass / footprint 190 of 4770 (U2D1), pads 627-728 of 3647")
	)
	(layers
		(0 "F.Cu" signal "TOP")
		(4 "In1.Cu" signal "L2GND")
		(6 "In2.Cu" signal "L3")
		(8 "In3.Cu" signal "L4GND")
		(10 "In4.Cu" signal "L5")
		(12 "In5.Cu" signal "L6GND")
		(14 "In6.Cu" signal "L7VCC")
		(16 "In7.Cu" signal "L8VCC")
		(18 "In8.Cu" signal "L9GND")
		(20 "In9.Cu" signal "L10")
		(22 "In10.Cu" signal "L11GND")
		(24 "In11.Cu" signal "L12")
		(26 "In12.Cu" signal "L13GND")
		(2 "B.Cu" signal "BOTTOM")
		(9 "F.Adhes" user "F.Adhesive")
		(11 "B.Adhes" user "B.Adhesive")
		(13 "F.Paste" user "Package Geometry/Pastemask Top")
		(15 "B.Paste" user "Package Geometry/Pastemask Bottom")
		(5 "F.SilkS" user "Ref Des/Silkscreen Top")
		(7 "B.SilkS" user "Ref Des/Silkscreen Bottom")
		(1 "F.Mask" user "Board Geometry/Soldermask Top")
		(3 "B.Mask" user "Board Geometry/Soldermask Bottom")
		(17 "Dwgs.User" user "User.Drawings")
		(19 "Cmts.User" user "User.Comments")
		(21 "Eco1.User" user "User.Eco1")
		(23 "Eco2.User" user "User.Eco2")
		(25 "Edge.Cuts" user "Board Geometry/Outline")
		(27 "Margin" user)
		(31 "F.CrtYd" user "Package Geometry/Place Bound Top")
		(29 "B.CrtYd" user "Package Geometry/Place Bound Bottom")
		(35 "F.Fab" user "Ref Des/Assembly Top")
		(33 "B.Fab" user "Ref Des/Assembly Bottom")
	)
	(footprint ""
		(layer "F.Cu")
		(at 104.99979 -76.550012 180)
		(property "Reference" "U2D1"
			(at 25.19299 30.484318 0)
			(unlocked yes)
			(layer "F.SilkS")
			(effects
				(font
					(size 0.7874 0.5842)
					(thickness 0.1524)
				)
			)
		)
		(property "Value" ""
			(at 0 0 180)
			(layer "F.Fab")
			(effects
				(font
					(size 1.27 1.27)
				)
			)
		)
		(duplicate_pad_numbers_are_jumpers no)
		(pad "AU26" smd circle
			(at -15.787878 -7.272274)
			(size 0.4318 0.4318)
			(layers "F.Cu" "F.Mask" "F.Paste")
			(net "GND")
		)
		(pad "AU28" smd circle
			(at -14.071092 -7.272274)
			(size 0.4318 0.4318)
			(layers "F.Cu" "F.Mask" "F.Paste")
			(net "GND")
		)
		(pad "AU58" smd circle
			(at 13.212572 -9.072372)
			(size 0.508 0.508)
			(layers "F.Cu" "F.Mask" "F.Paste")
			(net "PVCCIN_CPU1")
		)
		(pad "AU60" smd circle
			(at 14.929612 -9.072372)
			(size 0.4318 0.4318)
			(layers "F.Cu" "F.Mask" "F.Paste")
			(net "PVCCIN_CPU1")
		)
		(pad "AU62" smd circle
			(at 16.646398 -9.072372)
			(size 0.4318 0.4318)
			(layers "F.Cu" "F.Mask" "F.Paste")
			(net "GND")
		)
		(pad "AU64" smd circle
			(at 18.363438 -9.072372)
			(size 0.4318 0.4318)
			(layers "F.Cu" "F.Mask" "F.Paste")
			(net "GND")
		)
		(pad "AU66" smd circle
			(at 20.080478 -9.072372)
			(size 0.4318 0.4318)
			(layers "F.Cu" "F.Mask" "F.Paste")
			(net "M_J_DQS_DN<3>")
		)
		(pad "AU68" smd circle
			(at 21.797518 -9.072372)
			(size 0.4318 0.4318)
			(layers "F.Cu" "F.Mask" "F.Paste")
			(net "GND")
		)
		(pad "AU70" smd circle
			(at 23.514558 -9.072372)
			(size 0.4318 0.4318)
			(layers "F.Cu" "F.Mask" "F.Paste")
			(net "M_J_ECC<6>")
		)
		(pad "AU72" smd circle
			(at 25.231598 -9.072372)
			(size 0.4318 0.4318)
			(layers "F.Cu" "F.Mask" "F.Paste")
			(net "M_J_ECC<0>")
		)
		(pad "AU74" smd circle
			(at 26.948384 -9.072372)
			(size 0.4318 0.4318)
			(layers "F.Cu" "F.Mask" "F.Paste")
			(net "GND")
		)
		(pad "AU76" smd circle
			(at 28.665424 -9.072372)
			(size 0.4318 0.4318)
			(layers "F.Cu" "F.Mask" "F.Paste")
			(net "GND")
		)
		(pad "AU78" smd circle
			(at 30.382464 -9.072372)
			(size 0.4318 0.4318)
			(layers "F.Cu" "F.Mask" "F.Paste")
			(net "GND")
		)
		(pad "AU80" smd circle
			(at 32.099504 -9.072372)
			(size 0.4318 0.4318)
			(layers "F.Cu" "F.Mask" "F.Paste")
			(net "GND")
		)
		(pad "AU82" smd circle
			(at 33.816544 -9.072372)
			(size 0.4318 0.4318)
			(layers "F.Cu" "F.Mask" "F.Paste")
			(net "M_H_DQS_DN<9>")
		)
		(pad "AU84" smd circle
			(at 35.533584 -9.072372)
			(size 0.4318 0.4318)
			(layers "F.Cu" "F.Mask" "F.Paste")
			(net "GND")
		)
		(pad "AU86" smd custom
			(at 37.250624 -9.072372 270)
			(size 0.10795 0.10795)
			(layers "F.Cu" "F.Mask" "F.Paste")
			(net "GND")
			(options
				(clearance outline)
				(anchor circle)
			)
			(primitives
				(gr_poly
					(pts
						(arc
							(start 0.2159 -0.0381)
							(mid 0 -0.254)
							(end -0.2159 -0.0381)
						)
						(arc
							(start -0.2159 0.0381)
							(mid 0 0.254)
							(end 0.2159 0.0381)
						)
					)
					(width 0)
					(fill yes)
				)
			)
		)
		(pad "AV1" smd custom
			(at -37.250624 -6.777228 90)
			(size 0.10795 0.10795)
			(layers "F.Cu" "F.Mask" "F.Paste")
			(net "GND")
			(options
				(clearance outline)
				(anchor circle)
			)
			(primitives
				(gr_poly
					(pts
						(arc
							(start 0.2159 -0.0381)
							(mid 0 -0.254)
							(end -0.2159 -0.0381)
						)
						(arc
							(start -0.2159 0.0381)
							(mid 0 0.254)
							(end 0.2159 0.0381)
						)
					)
					(width 0)
					(fill yes)
				)
			)
		)
		(pad "AV3" smd circle
			(at -35.533584 -6.777228)
			(size 0.4318 0.4318)
			(layers "F.Cu" "F.Mask" "F.Paste")
			(net "GND")
		)
		(pad "AV5" smd circle
			(at -33.816544 -6.777228)
			(size 0.4318 0.4318)
			(layers "F.Cu" "F.Mask" "F.Paste")
			(net "UPI_CPU1_CPU0_P0P0_DP<15>")
		)
		(pad "AV7" smd circle
			(at -32.099504 -6.777228)
			(size 0.4318 0.4318)
			(layers "F.Cu" "F.Mask" "F.Paste")
			(net "GND")
		)
		(pad "AV9" smd circle
			(at -30.382464 -6.777228)
			(size 0.4318 0.4318)
			(layers "F.Cu" "F.Mask" "F.Paste")
			(net "UPI_CPU0_CPU1_P0P0_DP<16>")
		)
		(pad "AV11" smd circle
			(at -28.665424 -6.777228)
			(size 0.4318 0.4318)
			(layers "F.Cu" "F.Mask" "F.Paste")
			(net "GND")
		)
		(pad "AV13" smd circle
			(at -26.948384 -6.777228)
			(size 0.4318 0.4318)
			(layers "F.Cu" "F.Mask" "F.Paste")
			(net "GND")
		)
		(pad "AV15" smd circle
			(at -25.231598 -6.777228)
			(size 0.4318 0.4318)
			(layers "F.Cu" "F.Mask" "F.Paste")
			(net "PD_CPU1_TXT_PLTEN")
		)
		(pad "AV17" smd circle
			(at -23.514558 -6.777228)
			(size 0.4318 0.4318)
			(layers "F.Cu" "F.Mask" "F.Paste")
			(net "PU_CPU1_FRMAGENT")
		)
		(pad "AV19" smd circle
			(at -21.797518 -6.777228)
			(size 0.4318 0.4318)
			(layers "F.Cu" "F.Mask" "F.Paste")
			(net "GND")
		)
		(pad "AV21" smd circle
			(at -20.080478 -6.777228)
			(size 0.4318 0.4318)
			(layers "F.Cu" "F.Mask" "F.Paste")
			(net "CPU_XDP_PRESENT_N")
		)
		(pad "AV23" smd circle
			(at -18.363438 -6.777228)
			(size 0.4318 0.4318)
			(layers "F.Cu" "F.Mask" "F.Paste")
			(net "GND")
		)
		(pad "AV25" smd circle
			(at -16.646398 -6.777228)
			(size 0.4318 0.4318)
			(layers "F.Cu" "F.Mask" "F.Paste")
			(net "GND")
		)
		(pad "AV27" smd circle
			(at -14.929612 -6.777228)
			(size 0.4318 0.4318)
			(layers "F.Cu" "F.Mask" "F.Paste")
			(net "PVCCIO_CPU1")
		)
		(pad "AV59" smd circle
			(at 14.071092 -8.577326)
			(size 0.508 0.508)
			(layers "F.Cu" "F.Mask" "F.Paste")
			(net "PVCCIN_CPU1")
		)
		(pad "AV61" smd circle
			(at 15.787878 -8.577326)
			(size 0.4318 0.4318)
			(layers "F.Cu" "F.Mask" "F.Paste")
			(net "PVCCIN_CPU1")
		)
		(pad "AV63" smd circle
			(at 17.504918 -8.577326)
			(size 0.4318 0.4318)
			(layers "F.Cu" "F.Mask" "F.Paste")
			(net "GND")
		)
		(pad "AV65" smd circle
			(at 19.221958 -8.577326)
			(size 0.4318 0.4318)
			(layers "F.Cu" "F.Mask" "F.Paste")
			(net "GND")
		)
		(pad "AV67" smd circle
			(at 20.938998 -8.577326)
			(size 0.4318 0.4318)
			(layers "F.Cu" "F.Mask" "F.Paste")
			(net "GND")
		)
		(pad "AV69" smd circle
			(at 22.656038 -8.577326)
			(size 0.4318 0.4318)
			(layers "F.Cu" "F.Mask" "F.Paste")
			(net "M_J_ECC<2>")
		)
		(pad "AV71" smd circle
			(at 24.373078 -8.577326)
			(size 0.4318 0.4318)
			(layers "F.Cu" "F.Mask" "F.Paste")
			(net "M_J_DQS_DP<17>")
		)
		(pad "AV73" smd circle
			(at 26.090118 -8.577326)
			(size 0.4318 0.4318)
			(layers "F.Cu" "F.Mask" "F.Paste")
			(net "M_J_ECC<4>")
		)
		(pad "AV75" smd circle
			(at 27.806904 -8.577326)
			(size 0.4318 0.4318)
			(layers "F.Cu" "F.Mask" "F.Paste")
			(net "GND")
		)
		(pad "AV77" smd circle
			(at 29.523944 -8.577326)
			(size 0.4318 0.4318)
			(layers "F.Cu" "F.Mask" "F.Paste")
			(net "TP_CPU1_RSVD_186")
		)
		(pad "AV79" smd circle
			(at 31.240984 -8.577326)
			(size 0.4318 0.4318)
			(layers "F.Cu" "F.Mask" "F.Paste")
			(net "M_H_DQ<5>")
		)
		(pad "AV81" smd circle
			(at 32.958024 -8.577326)
			(size 0.4318 0.4318)
			(layers "F.Cu" "F.Mask" "F.Paste")
			(net "M_H_DQ<0>")
		)
		(pad "AV83" smd circle
			(at 34.675064 -8.577326)
			(size 0.4318 0.4318)
			(layers "F.Cu" "F.Mask" "F.Paste")
			(net "GND")
		)
		(pad "AV85" smd circle
			(at 36.392104 -8.577326)
			(size 0.4318 0.4318)
			(layers "F.Cu" "F.Mask" "F.Paste")
			(net "VSENSE_VCCINR2PMAX_CPU1")
		)
		(pad "AW2" smd custom
			(at -36.392104 -6.281928 90)
			(size 0.10795 0.10795)
			(layers "F.Cu" "F.Mask" "F.Paste")
			(net "GND")
			(options
				(clearance outline)
				(anchor circle)
			)
			(primitives
				(gr_poly
					(pts
						(arc
							(start 0.2159 -0.0381)
							(mid 0 -0.254)
							(end -0.2159 -0.0381)
						)
						(arc
							(start -0.2159 0.0381)
							(mid 0 0.254)
							(end 0.2159 0.0381)
						)
					)
					(width 0)
					(fill yes)
				)
			)
		)
		(pad "AW4" smd circle
			(at -34.675064 -6.281928)
			(size 0.4318 0.4318)
			(layers "F.Cu" "F.Mask" "F.Paste")
			(net "UPI_CPU1_CPU0_P0P0_DN<15>")
		)
		(pad "AW6" smd circle
			(at -32.958024 -6.281928)
			(size 0.4318 0.4318)
			(layers "F.Cu" "F.Mask" "F.Paste")
			(net "PVCCIO_CPU1")
		)
		(pad "AW8" smd circle
			(at -31.240984 -6.281928)
			(size 0.4318 0.4318)
			(layers "F.Cu" "F.Mask" "F.Paste")
			(net "UPI_CPU0_CPU1_P0P0_DN<16>")
		)
		(pad "AW10" smd circle
			(at -29.523944 -6.281928)
			(size 0.4318 0.4318)
			(layers "F.Cu" "F.Mask" "F.Paste")
			(net "GND")
		)
		(pad "AW12" smd circle
			(at -27.806904 -6.281928)
			(size 0.4318 0.4318)
			(layers "F.Cu" "F.Mask" "F.Paste")
			(net "PD_CPU1_DMIMODE_OVERRIDE")
		)
		(pad "AW14" smd circle
			(at -26.090118 -6.281928)
			(size 0.4318 0.4318)
			(layers "F.Cu" "F.Mask" "F.Paste")
			(net "PD_CPU1_KSFC_DIS")
		)
		(pad "AW16" smd circle
			(at -24.373078 -6.281928)
			(size 0.4318 0.4318)
			(layers "F.Cu" "F.Mask" "F.Paste")
			(net "TP_CPU1_TEST_8")
		)
		(pad "AW18" smd circle
			(at -22.656038 -6.281928)
			(size 0.4318 0.4318)
			(layers "F.Cu" "F.Mask" "F.Paste")
			(net "PU_CPU1_TXT_AGENT")
		)
		(pad "AW20" smd circle
			(at -20.938998 -6.281928)
			(size 0.4318 0.4318)
			(layers "F.Cu" "F.Mask" "F.Paste")
			(net "TP_CPU1_TEST_9")
		)
		(pad "AW22" smd circle
			(at -19.221958 -6.281928)
			(size 0.4318 0.4318)
			(layers "F.Cu" "F.Mask" "F.Paste")
			(net "TP_CPU1_TEST_10")
		)
		(pad "AW24" smd circle
			(at -17.504918 -6.281928)
			(size 0.4318 0.4318)
			(layers "F.Cu" "F.Mask" "F.Paste")
			(net "CLK_100M_CPU1_BCLK0_DP")
		)
		(pad "AW26" smd circle
			(at -15.787878 -6.281928)
			(size 0.4318 0.4318)
			(layers "F.Cu" "F.Mask" "F.Paste")
			(net "PVCCIO_CPU1")
		)
		(pad "AW60" smd circle
			(at 14.929612 -8.081772)
			(size 0.508 0.508)
			(layers "F.Cu" "F.Mask" "F.Paste")
			(net "PVCCIN_CPU1")
		)
		(pad "AW62" smd circle
			(at 16.646398 -8.081772)
			(size 0.4318 0.4318)
			(layers "F.Cu" "F.Mask" "F.Paste")
			(net "GND")
		)
		(pad "AW64" smd circle
			(at 18.363438 -8.081772)
			(size 0.4318 0.4318)
			(layers "F.Cu" "F.Mask" "F.Paste")
			(net "TP_CPU1_RSVD_184")
		)
		(pad "AW66" smd circle
			(at 20.080478 -8.081772)
			(size 0.4318 0.4318)
			(layers "F.Cu" "F.Mask" "F.Paste")
			(net "GND")
		)
		(pad "AW68" smd circle
			(at 21.797518 -8.081772)
			(size 0.4318 0.4318)
			(layers "F.Cu" "F.Mask" "F.Paste")
			(net "GND")
		)
		(pad "AW70" smd circle
			(at 23.514558 -8.081772)
			(size 0.4318 0.4318)
			(layers "F.Cu" "F.Mask" "F.Paste")
			(net "GND")
		)
		(pad "AW72" smd circle
			(at 25.231598 -8.081772)
			(size 0.4318 0.4318)
			(layers "F.Cu" "F.Mask" "F.Paste")
			(net "GND")
		)
		(pad "AW74" smd circle
			(at 26.948384 -8.081772)
			(size 0.4318 0.4318)
			(layers "F.Cu" "F.Mask" "F.Paste")
			(net "GND")
		)
		(pad "AW76" smd circle
			(at 28.665424 -8.081772)
			(size 0.4318 0.4318)
			(layers "F.Cu" "F.Mask" "F.Paste")
			(net "TP_CPU1_RSVD_183")
		)
		(pad "AW78" smd circle
			(at 30.382464 -8.081772)
			(size 0.4318 0.4318)
			(layers "F.Cu" "F.Mask" "F.Paste")
			(net "GND")
		)
		(pad "AW80" smd circle
			(at 32.099504 -8.081772)
			(size 0.4318 0.4318)
			(layers "F.Cu" "F.Mask" "F.Paste")
			(net "M_H_DQ<4>")
		)
		(pad "AW82" smd circle
			(at 33.816544 -8.081772)
			(size 0.4318 0.4318)
			(layers "F.Cu" "F.Mask" "F.Paste")
			(net "GND")
		)
		(pad "AW84" smd circle
			(at 35.533584 -8.081772)
			(size 0.4318 0.4318)
			(layers "F.Cu" "F.Mask" "F.Paste")
			(net "GND")
		)
		(pad "AW86" smd custom
			(at 37.250624 -8.081772 270)
			(size 0.10795 0.10795)
			(layers "F.Cu" "F.Mask" "F.Paste")
			(net "VSENSE_VCCINR2PMAX_CPU1")
			(options
				(clearance outline)
				(anchor circle)
			)
			(primitives
				(gr_poly
					(pts
						(arc
							(start 0.2159 -0.0381)
							(mid 0 -0.254)
							(end -0.2159 -0.0381)
						)
						(arc
							(start -0.2159 0.0381)
							(mid 0 0.254)
							(end 0.2159 0.0381)
						)
					)
					(width 0)
					(fill yes)
				)
			)
		)
		(pad "AY3" smd circle
			(at -35.533584 -5.786628)
			(size 0.4318 0.4318)
			(layers "F.Cu" "F.Mask" "F.Paste")
			(net "UPI_CPU1_CPU0_P0P0_DN<16>")
		)
		(pad "AY5" smd circle
			(at -33.816544 -5.786628)
			(size 0.4318 0.4318)
			(layers "F.Cu" "F.Mask" "F.Paste")
			(net "GND")
		)
		(pad "AY7" smd circle
			(at -32.099504 -5.786628)
			(size 0.4318 0.4318)
			(layers "F.Cu" "F.Mask" "F.Paste")
			(net "UPI_CPU0_CPU1_P0P0_DP<13>")
		)
		(pad "AY9" smd circle
			(at -30.382464 -5.786628)
			(size 0.4318 0.4318)
			(layers "F.Cu" "F.Mask" "F.Paste")
			(net "UPI_CPU0_CPU1_P0P0_DN<17>")
		)
		(pad "AY11" smd circle
			(at -28.665424 -5.786628)
			(size 0.4318 0.4318)
			(layers "F.Cu" "F.Mask" "F.Paste")
			(net "PVCCIO_CPU1")
		)
		(pad "AY13" smd circle
			(at -26.948384 -5.786628)
			(size 0.4318 0.4318)
			(layers "F.Cu" "F.Mask" "F.Paste")
			(net "TP_CPU1_RSVD_TEST_11")
		)
		(pad "AY15" smd circle
			(at -25.231598 -5.786628)
			(size 0.4318 0.4318)
			(layers "F.Cu" "F.Mask" "F.Paste")
			(net "GND")
		)
		(pad "AY17" smd circle
			(at -23.514558 -5.786628)
			(size 0.4318 0.4318)
			(layers "F.Cu" "F.Mask" "F.Paste")
			(net "GND")
		)
		(pad "AY19" smd circle
			(at -21.797518 -5.786628)
			(size 0.4318 0.4318)
			(layers "F.Cu" "F.Mask" "F.Paste")
			(net "PD_CPU1_TEST12")
		)
		(pad "AY21" smd circle
			(at -20.080478 -5.786628)
			(size 0.4318 0.4318)
			(layers "F.Cu" "F.Mask" "F.Paste")
			(net "GND")
		)
		(pad "AY23" smd circle
			(at -18.363438 -5.786628)
			(size 0.4318 0.4318)
			(layers "F.Cu" "F.Mask" "F.Paste")
			(net "GND")
		)
		(pad "AY25" smd circle
			(at -16.646398 -5.786628)
			(size 0.4318 0.4318)
			(layers "F.Cu" "F.Mask" "F.Paste")
			(net "GND")
		)
		(pad "AY27" smd circle
			(at -14.929612 -5.786628)
			(size 0.4318 0.4318)
			(layers "F.Cu" "F.Mask" "F.Paste")
			(net "PVCCIO_CPU1")
		)
		(pad "AY61" smd circle
			(at 15.787878 -7.586726)
			(size 0.4318 0.4318)
			(layers "F.Cu" "F.Mask" "F.Paste")
			(net "PVCCIN_CPU1")
		)
		(pad "AY63" smd circle
			(at 17.504918 -7.586726)
			(size 0.4318 0.4318)
			(layers "F.Cu" "F.Mask" "F.Paste")
			(net "GND")
		)
		(pad "AY65" smd circle
			(at 19.221958 -7.586726)
			(size 0.4318 0.4318)
			(layers "F.Cu" "F.Mask" "F.Paste")
			(net "TP_CPU1_RSVD_182")
		)
		(pad "AY67" smd circle
			(at 20.938998 -7.586726)
			(size 0.4318 0.4318)
			(layers "F.Cu" "F.Mask" "F.Paste")
			(net "TP_CPU1_RSVD_181")
		)
		(pad "AY69" smd circle
			(at 22.656038 -7.586726)
			(size 0.4318 0.4318)
			(layers "F.Cu" "F.Mask" "F.Paste")
			(net "M_J_ECC<3>")
		)
		(pad "AY71" smd circle
			(at 24.373078 -7.586726)
			(size 0.4318 0.4318)
			(layers "F.Cu" "F.Mask" "F.Paste")
			(net "M_J_DQS_DP<8>")
		)
		(pad "AY73" smd circle
			(at 26.090118 -7.586726)
			(size 0.4318 0.4318)
			(layers "F.Cu" "F.Mask" "F.Paste")
			(net "M_J_ECC<5>")
		)
		(pad "AY75" smd circle
			(at 27.806904 -7.586726)
			(size 0.4318 0.4318)
			(layers "F.Cu" "F.Mask" "F.Paste")
			(net "TP_CPU1_RSVD_180")
		)
		(pad "AY77" smd circle
			(at 29.523944 -7.586726)
			(size 0.4318 0.4318)
			(layers "F.Cu" "F.Mask" "F.Paste")
			(net "TP_CPU1_RSVD_179")
		)
		(pad "AY79" smd circle
			(at 31.240984 -7.586726)
			(size 0.4318 0.4318)
			(layers "F.Cu" "F.Mask" "F.Paste")
			(net "GND")
		)
		(pad "AY81" smd circle
			(at 32.958024 -7.586726)
			(size 0.4318 0.4318)
			(layers "F.Cu" "F.Mask" "F.Paste")
			(net "GND")
		)
		(pad "AY83" smd circle
			(at 34.675064 -7.586726)
			(size 0.4318 0.4318)
			(layers "F.Cu" "F.Mask" "F.Paste")
			(net "TP_CPU1_RSVD_255")
		)
		(pad "AY85" smd circle
			(at 36.392104 -7.586726)
			(size 0.4318 0.4318)
			(layers "F.Cu" "F.Mask" "F.Paste")
			(net "VSENSE_PVCCIN_CPU1_SKT_VRTN")
		)
		(pad "B3" smd custom
			(at -35.533584 -24.608028 45)
			(size 0.10795 0.10795)
			(layers "F.Cu" "F.Mask" "F.Paste")
			(net "TP_CPU1_RSVD_299")
			(options
				(clearance outline)
				(anchor circle)
			)
			(primitives
				(gr_poly
					(pts
						(arc
							(start 0.2159 -0.0381)
							(mid 0 -0.254)
							(end -0.2159 -0.0381)
						)
						(arc
							(start -0.2159 0.0381)
							(mid 0 0.254)
							(end 0.2159 0.0381)
						)
					)
					(width 0)
					(fill yes)
				)
			)
		)
		(pad "B5" smd custom
			(at -33.816544 -24.608028 45)
			(size 0.10795 0.10795)
			(layers "F.Cu" "F.Mask" "F.Paste")
			(net "GND")
			(options
				(clearance outline)
				(anchor circle)
			)
			(primitives
				(gr_poly
					(pts
						(arc
							(start 0.2159 -0.0381)
							(mid 0 -0.254)
							(end -0.2159 -0.0381)
						)
						(arc
							(start -0.2159 0.0381)
							(mid 0 0.254)
							(end 0.2159 0.0381)
						)
					)
					(width 0)
					(fill yes)
				)
			)
		)
		(pad "B7" smd custom
			(at -32.099504 -24.608028)
			(size 0.10795 0.10795)
			(layers "F.Cu" "F.Mask" "F.Paste")
			(net "TP_CPU1_RSVD_298")
			(options
				(clearance outline)
				(anchor circle)
			)
			(primitives
				(gr_poly
					(pts
						(arc
							(start 0.2159 -0.0381)
							(mid 0 -0.254)
							(end -0.2159 -0.0381)
						)
						(arc
							(start -0.2159 0.0381)
							(mid 0 0.254)
							(end 0.2159 0.0381)
						)
					)
					(width 0)
					(fill yes)
				)
			)
		)
		(pad "B9" smd circle
			(at -30.382464 -24.608028)
			(size 0.4318 0.4318)
			(layers "F.Cu" "F.Mask" "F.Paste")
			(net "GND")
		)
	)
)
